(kicad_pcb
	(version 20260206)
	(generator "pcbnew")
	(generator_version "10.0")
	(general
		(thickness 1.6)
		(legacy_teardrops no)
	)
	(paper "A4")
	(title_block
		(title "9054_F0T_PDB_BD_GPU_F_V04_1213_1550_OCP.brd")
		(comment 1 "Grand Teton / footprints 104-111 of 608")
	)
	(layers
		(0 "F.Cu" signal "TOP")
		(4 "In1.Cu" signal "GND")
		(6 "In2.Cu" signal "IN1")
		(8 "In3.Cu" signal "GND1")
		(10 "In4.Cu" signal "VCC")
		(12 "In5.Cu" signal "VCC1")
		(14 "In6.Cu" signal "GND2")
		(16 "In7.Cu" signal "IN2")
		(18 "In8.Cu" signal "GND3")
		(2 "B.Cu" signal "BOTTOM")
		(9 "F.Adhes" user "F.Adhesive")
		(11 "B.Adhes" user "B.Adhesive")
		(13 "F.Paste" user "Package Geometry/Pastemask Top")
		(15 "B.Paste" user "Package Geometry/Pastemask Bottom")
		(5 "F.SilkS" user "Ref Des/Silkscreen Top")
		(7 "B.SilkS" user "Ref Des/Silkscreen Bottom")
		(1 "F.Mask" user "Board Geometry/Soldermask Top")
		(3 "B.Mask" user "Board Geometry/Soldermask Bottom")
		(17 "Dwgs.User" user "User.Drawings")
		(19 "Cmts.User" user "User.Comments")
		(21 "Eco1.User" user "User.Eco1")
		(23 "Eco2.User" user "User.Eco2")
		(25 "Edge.Cuts" user "Board Geometry/Outline")
		(27 "Margin" user)
		(31 "F.CrtYd" user "Package Geometry/Place Bound Top")
		(29 "B.CrtYd" user "Package Geometry/Place Bound Bottom")
		(35 "F.Fab" user "Ref Des/Assembly Top")
		(33 "B.Fab" user "Ref Des/Assembly Bottom")
	)
	(footprint ""
		(layer "F.Cu")
		(at 435.5338 -25.146 180)
		(property "Reference" "R61"
			(at 0 0 180)
			(layer "F.SilkS")
			(hide yes)
			(effects
				(font
					(size 1.27 1.27)
				)
			)
		)
		(property "Value" ""
			(at 0 0 180)
			(layer "F.Fab")
			(effects
				(font
					(size 1.27 1.27)
				)
			)
		)
		(duplicate_pad_numbers_are_jumpers no)
		(fp_line
			(start 0.7874 0.4064)
			(end -0.7874 0.4064)
			(stroke
				(width 0.1524)
				(type default)
			)
			(layer "F.SilkS")
		)
		(fp_line
			(start 0.7874 -0.4064)
			(end 0.7874 0.4064)
			(stroke
				(width 0.1524)
				(type default)
			)
			(layer "F.SilkS")
		)
		(fp_line
			(start -0.7874 0.4064)
			(end -0.7874 -0.4064)
			(stroke
				(width 0.1524)
				(type default)
			)
			(layer "F.SilkS")
		)
		(fp_line
			(start -0.7874 -0.4064)
			(end 0.7874 -0.4064)
			(stroke
				(width 0.1524)
				(type default)
			)
			(layer "F.SilkS")
		)
		(fp_line
			(start 0.67945 0.3048)
			(end 0.120396 0.3048)
			(stroke
				(width 0.1)
				(type default)
			)
			(layer "F.Fab")
		)
		(fp_line
			(start 0.67945 -0.3048)
			(end 0.67945 0.3048)
			(stroke
				(width 0.1)
				(type default)
			)
			(layer "F.Fab")
		)
		(fp_line
			(start 0.12065 -0.2794)
			(end 0.12065 -0.3048)
			(stroke
				(width 0.1)
				(type default)
			)
			(layer "F.Fab")
		)
		(fp_line
			(start 0.12065 -0.3048)
			(end 0.67945 -0.3048)
			(stroke
				(width 0.1)
				(type default)
			)
			(layer "F.Fab")
		)
		(fp_line
			(start 0.120396 0.3048)
			(end 0.120396 0.2794)
			(stroke
				(width 0.1)
				(type default)
			)
			(layer "F.Fab")
		)
		(fp_line
			(start 0.120396 0.2794)
			(end -0.12065 0.2794)
			(stroke
				(width 0.1)
				(type default)
			)
			(layer "F.Fab")
		)
		(fp_line
			(start -0.12065 0.3048)
			(end -0.67945 0.3048)
			(stroke
				(width 0.1)
				(type default)
			)
			(layer "F.Fab")
		)
		(fp_line
			(start -0.12065 0.2794)
			(end -0.12065 0.3048)
			(stroke
				(width 0.1)
				(type default)
			)
			(layer "F.Fab")
		)
		(fp_line
			(start -0.12065 -0.2794)
			(end 0.12065 -0.2794)
			(stroke
				(width 0.1)
				(type default)
			)
			(layer "F.Fab")
		)
		(fp_line
			(start -0.12065 -0.305054)
			(end -0.12065 -0.2794)
			(stroke
				(width 0.1)
				(type default)
			)
			(layer "F.Fab")
		)
		(fp_line
			(start -0.67945 0.3048)
			(end -0.67945 -0.305054)
			(stroke
				(width 0.1)
				(type default)
			)
			(layer "F.Fab")
		)
		(fp_line
			(start -0.67945 -0.305054)
			(end -0.12065 -0.305054)
			(stroke
				(width 0.1)
				(type default)
			)
			(layer "F.Fab")
		)
		(pad "1" smd circle
			(at -0.40005 0 180)
			(size 0 0)
			(layers "F.Cu" "F.Mask" "F.Paste")
			(net "P3V3_AUX")
		)
		(pad "2" smd circle
			(at 0.40005 0 180)
			(size 0 0)
			(layers "F.Cu" "F.Mask" "F.Paste")
			(net "FRU_ADDR0")
		)
	)
	(footprint ""
		(layer "F.Cu")
		(at 250.000008 -87.499952 180)
		(property "Reference" "H8"
			(at 0.699008 -5.484622 0)
			(unlocked yes)
			(layer "F.SilkS")
			(effects
				(font
					(size 0.7874 0.5842)
					(thickness 0.1524)
				)
				(justify left)
			)
		)
		(property "Value" ""
			(at 0 0 180)
			(layer "F.Fab")
			(effects
				(font
					(size 1.27 1.27)
				)
			)
		)
		(duplicate_pad_numbers_are_jumpers no)
		(pad "1" thru_hole oval
			(at 0 0 180)
			(size 9.017 14.0208)
			(drill 3.0226
				(offset 0 2.499868)
			)
			(layers "*.Cu" "*.Mask")
			(remove_unused_layers no)
			(net "GND")
			(clearance -1.500378)
			(padstack
				(mode front_inner_back)
				(layer "Inner"
					(shape circle)
					(size 0 0)
					(clearance 0)
				)
				(layer "B.Cu"
					(shape oval)
					(size 9.017 14.0208)
					(offset 0 2.499868)
					(clearance -1.500378)
				)
			)
		)
	)
	(footprint ""
		(layer "F.Cu")
		(at 14.99997 -104.544876)
		(property "Reference" "H21"
			(at -1.02997 -8.839454 0)
			(unlocked yes)
			(layer "F.SilkS")
			(effects
				(font
					(size 0.7874 0.5842)
					(thickness 0.1524)
				)
				(justify left)
			)
		)
		(property "Value" ""
			(at 0 0 0)
			(layer "F.Fab")
			(effects
				(font
					(size 1.27 1.27)
				)
			)
		)
		(duplicate_pad_numbers_are_jumpers no)
		(fp_circle
			(center 0 0)
			(end 7.999984 0)
			(stroke
				(width 0.1524)
				(type default)
			)
			(fill no)
			(layer "F.SilkS")
		)
		(fp_circle
			(center 0 0)
			(end 7.999984 0)
			(stroke
				(width 0.1524)
				(type default)
			)
			(fill no)
			(layer "B.SilkS")
		)
		(fp_circle
			(center 0 0)
			(end 7.999984 0)
			(stroke
				(width 0.1)
				(type default)
			)
			(fill no)
			(layer "B.Fab")
		)
		(fp_circle
			(center 0 0)
			(end 7.999984 0)
			(stroke
				(width 0.1)
				(type default)
			)
			(fill no)
			(layer "F.Fab")
		)
		(pad "" np_thru_hole circle
			(at 0 0)
			(size 4.0132 4.0132)
			(drill 4.0132)
			(layers "*.Cu" "*.Mask")
			(clearance 0.381)
			(thermal_gap 0.381)
		)
		(pad "2" thru_hole circle
			(at 0 -3.50012)
			(size 0.762 0.762)
			(drill 0.5588)
			(layers "*.Cu" "*.Mask")
			(remove_unused_layers no)
			(net "GND")
			(clearance 0.1524)
			(thermal_gap 0.1524)
		)
		(pad "3" thru_hole circle
			(at -2.500122 -2.500122)
			(size 0.762 0.762)
			(drill 0.5588)
			(layers "*.Cu" "*.Mask")
			(remove_unused_layers no)
			(net "GND")
			(clearance 0.1524)
			(thermal_gap 0.1524)
		)
		(pad "4" thru_hole circle
			(at -3.50012 0)
			(size 0.762 0.762)
			(drill 0.5588)
			(layers "*.Cu" "*.Mask")
			(remove_unused_layers no)
			(net "GND")
			(clearance 0.1524)
			(thermal_gap 0.1524)
		)
		(pad "5" thru_hole circle
			(at -2.500122 2.500122)
			(size 0.762 0.762)
			(drill 0.5588)
			(layers "*.Cu" "*.Mask")
			(remove_unused_layers no)
			(net "GND")
			(clearance 0.1524)
			(thermal_gap 0.1524)
		)
		(pad "6" thru_hole circle
			(at 0 3.50012)
			(size 0.762 0.762)
			(drill 0.5588)
			(layers "*.Cu" "*.Mask")
			(remove_unused_layers no)
			(net "GND")
			(clearance 0.1524)
			(thermal_gap 0.1524)
		)
		(pad "7" thru_hole circle
			(at 2.500122 2.500122)
			(size 0.762 0.762)
			(drill 0.5588)
			(layers "*.Cu" "*.Mask")
			(remove_unused_layers no)
			(net "GND")
			(clearance 0.1524)
			(thermal_gap 0.1524)
		)
		(pad "8" thru_hole circle
			(at 3.50012 0)
			(size 0.762 0.762)
			(drill 0.5588)
			(layers "*.Cu" "*.Mask")
			(remove_unused_layers no)
			(net "GND")
			(clearance 0.1524)
			(thermal_gap 0.1524)
		)
		(pad "9" thru_hole circle
			(at 2.500122 -2.500122)
			(size 0.762 0.762)
			(drill 0.5588)
			(layers "*.Cu" "*.Mask")
			(remove_unused_layers no)
			(net "GND")
			(clearance 0.1524)
			(thermal_gap 0.1524)
		)
		(zone
			(layers "F.Cu" "B.Cu" "In1.Cu" "In2.Cu" "In3.Cu" "In4.Cu" "In5.Cu" "In6.Cu"
				"In7.Cu" "In8.Cu"
			)
			(hatch none 0.5)
			(connect_pads
				(clearance 0)
			)
			(min_thickness 0.25)
			(keepout
				(tracks not_allowed)
				(vias allowed)
				(pads allowed)
				(copperpour not_allowed)
				(footprints allowed)
			)
			(placement
				(enabled no)
				(sheetname "")
			)
			(fill
				(thermal_gap 0.5)
				(thermal_bridge_width 0.5)
				(island_removal_mode 0)
			)
			(polygon
				(pts
					(arc
						(start 17.51457 -104.544876)
						(mid 12.48537 -104.544876)
						(end 17.51457 -104.544876)
					)
				)
			)
		)
	)
	(footprint ""
		(layer "F.Cu")
		(at 190.000128 -87.499952 180)
		(property "Reference" "H6"
			(at 0.643128 -5.484622 0)
			(unlocked yes)
			(layer "F.SilkS")
			(effects
				(font
					(size 0.7874 0.5842)
					(thickness 0.1524)
				)
				(justify left)
			)
		)
		(property "Value" ""
			(at 0 0 180)
			(layer "F.Fab")
			(effects
				(font
					(size 1.27 1.27)
				)
			)
		)
		(duplicate_pad_numbers_are_jumpers no)
		(pad "1" thru_hole oval
			(at 0 0 180)
			(size 9.017 14.0208)
			(drill 3.0226
				(offset 0 2.499868)
			)
			(layers "*.Cu" "*.Mask")
			(remove_unused_layers no)
			(net "GND")
			(clearance -1.500378)
			(padstack
				(mode front_inner_back)
				(layer "Inner"
					(shape circle)
					(size 0 0)
					(clearance 0)
				)
				(layer "B.Cu"
					(shape oval)
					(size 9.017 14.0208)
					(offset 0 2.499868)
					(clearance -1.500378)
				)
			)
		)
	)
	(footprint ""
		(layer "F.Cu")
		(at 168.956736 -66.167)
		(property "Reference" "R5891"
			(at 0 0 0)
			(layer "F.SilkS")
			(hide yes)
			(effects
				(font
					(size 1.27 1.27)
				)
			)
		)
		(property "Value" ""
			(at 0 0 0)
			(layer "F.Fab")
			(effects
				(font
					(size 1.27 1.27)
				)
			)
		)
		(duplicate_pad_numbers_are_jumpers no)
		(fp_line
			(start -0.7874 -0.4064)
			(end 0.7874 -0.4064)
			(stroke
				(width 0.1524)
				(type default)
			)
			(layer "F.SilkS")
		)
		(fp_line
			(start -0.7874 0.4064)
			(end -0.7874 -0.4064)
			(stroke
				(width 0.1524)
				(type default)
			)
			(layer "F.SilkS")
		)
		(fp_line
			(start 0.7874 -0.4064)
			(end 0.7874 0.4064)
			(stroke
				(width 0.1524)
				(type default)
			)
			(layer "F.SilkS")
		)
		(fp_line
			(start 0.7874 0.4064)
			(end -0.7874 0.4064)
			(stroke
				(width 0.1524)
				(type default)
			)
			(layer "F.SilkS")
		)
		(fp_line
			(start -0.67945 -0.305054)
			(end -0.12065 -0.305054)
			(stroke
				(width 0.1)
				(type default)
			)
			(layer "F.Fab")
		)
		(fp_line
			(start -0.67945 0.3048)
			(end -0.67945 -0.305054)
			(stroke
				(width 0.1)
				(type default)
			)
			(layer "F.Fab")
		)
		(fp_line
			(start -0.12065 -0.305054)
			(end -0.12065 -0.2794)
			(stroke
				(width 0.1)
				(type default)
			)
			(layer "F.Fab")
		)
		(fp_line
			(start -0.12065 -0.2794)
			(end 0.12065 -0.2794)
			(stroke
				(width 0.1)
				(type default)
			)
			(layer "F.Fab")
		)
		(fp_line
			(start -0.12065 0.2794)
			(end -0.12065 0.3048)
			(stroke
				(width 0.1)
				(type default)
			)
			(layer "F.Fab")
		)
		(fp_line
			(start -0.12065 0.3048)
			(end -0.67945 0.3048)
			(stroke
				(width 0.1)
				(type default)
			)
			(layer "F.Fab")
		)
		(fp_line
			(start 0.120396 0.2794)
			(end -0.12065 0.2794)
			(stroke
				(width 0.1)
				(type default)
			)
			(layer "F.Fab")
		)
		(fp_line
			(start 0.120396 0.3048)
			(end 0.120396 0.2794)
			(stroke
				(width 0.1)
				(type default)
			)
			(layer "F.Fab")
		)
		(fp_line
			(start 0.12065 -0.3048)
			(end 0.67945 -0.3048)
			(stroke
				(width 0.1)
				(type default)
			)
			(layer "F.Fab")
		)
		(fp_line
			(start 0.12065 -0.2794)
			(end 0.12065 -0.3048)
			(stroke
				(width 0.1)
				(type default)
			)
			(layer "F.Fab")
		)
		(fp_line
			(start 0.67945 -0.3048)
			(end 0.67945 0.3048)
			(stroke
				(width 0.1)
				(type default)
			)
			(layer "F.Fab")
		)
		(fp_line
			(start 0.67945 0.3048)
			(end 0.120396 0.3048)
			(stroke
				(width 0.1)
				(type default)
			)
			(layer "F.Fab")
		)
		(pad "1" smd circle
			(at -0.40005 0)
			(size 0 0)
			(layers "F.Cu" "F.Mask" "F.Paste")
			(net "P52V_HS2_VCAP")
		)
		(pad "2" smd circle
			(at 0.40005 0)
			(size 0 0)
			(layers "F.Cu" "F.Mask" "F.Paste")
			(net "P52V_HS2_ADR0")
		)
	)
	(footprint ""
		(layer "F.Cu")
		(at 318.008 -83.82 180)
		(property "Reference" "PR6968"
			(at 0 0 180)
			(layer "F.SilkS")
			(hide yes)
			(effects
				(font
					(size 1.27 1.27)
				)
			)
		)
		(property "Value" ""
			(at 0 0 180)
			(layer "F.Fab")
			(effects
				(font
					(size 1.27 1.27)
				)
			)
		)
		(duplicate_pad_numbers_are_jumpers no)
		(fp_line
			(start 0.7874 0.4064)
			(end -0.7874 0.4064)
			(stroke
				(width 0.1524)
				(type default)
			)
			(layer "F.SilkS")
		)
		(fp_line
			(start 0.7874 -0.4064)
			(end 0.7874 0.4064)
			(stroke
				(width 0.1524)
				(type default)
			)
			(layer "F.SilkS")
		)
		(fp_line
			(start -0.7874 0.4064)
			(end -0.7874 -0.4064)
			(stroke
				(width 0.1524)
				(type default)
			)
			(layer "F.SilkS")
		)
		(fp_line
			(start -0.7874 -0.4064)
			(end 0.7874 -0.4064)
			(stroke
				(width 0.1524)
				(type default)
			)
			(layer "F.SilkS")
		)
		(fp_line
			(start 0.67945 0.3048)
			(end 0.120396 0.3048)
			(stroke
				(width 0.1)
				(type default)
			)
			(layer "F.Fab")
		)
		(fp_line
			(start 0.67945 -0.3048)
			(end 0.67945 0.3048)
			(stroke
				(width 0.1)
				(type default)
			)
			(layer "F.Fab")
		)
		(fp_line
			(start 0.12065 -0.2794)
			(end 0.12065 -0.3048)
			(stroke
				(width 0.1)
				(type default)
			)
			(layer "F.Fab")
		)
		(fp_line
			(start 0.12065 -0.3048)
			(end 0.67945 -0.3048)
			(stroke
				(width 0.1)
				(type default)
			)
			(layer "F.Fab")
		)
		(fp_line
			(start 0.120396 0.3048)
			(end 0.120396 0.2794)
			(stroke
				(width 0.1)
				(type default)
			)
			(layer "F.Fab")
		)
		(fp_line
			(start 0.120396 0.2794)
			(end -0.12065 0.2794)
			(stroke
				(width 0.1)
				(type default)
			)
			(layer "F.Fab")
		)
		(fp_line
			(start -0.12065 0.3048)
			(end -0.67945 0.3048)
			(stroke
				(width 0.1)
				(type default)
			)
			(layer "F.Fab")
		)
		(fp_line
			(start -0.12065 0.2794)
			(end -0.12065 0.3048)
			(stroke
				(width 0.1)
				(type default)
			)
			(layer "F.Fab")
		)
		(fp_line
			(start -0.12065 -0.2794)
			(end 0.12065 -0.2794)
			(stroke
				(width 0.1)
				(type default)
			)
			(layer "F.Fab")
		)
		(fp_line
			(start -0.12065 -0.305054)
			(end -0.12065 -0.2794)
			(stroke
				(width 0.1)
				(type default)
			)
			(layer "F.Fab")
		)
		(fp_line
			(start -0.67945 0.3048)
			(end -0.67945 -0.305054)
			(stroke
				(width 0.1)
				(type default)
			)
			(layer "F.Fab")
		)
		(fp_line
			(start -0.67945 -0.305054)
			(end -0.12065 -0.305054)
			(stroke
				(width 0.1)
				(type default)
			)
			(layer "F.Fab")
		)
		(pad "1" smd rect
			(at -0.40005 0)
			(size 0.4572 0.508)
			(layers "F.Cu" "F.Mask" "F.Paste")
			(net "P52V_HS1_TEMPN")
		)
		(pad "2" smd rect
			(at 0.40005 0)
			(size 0.4572 0.508)
			(layers "F.Cu" "F.Mask" "F.Paste")
			(net "P52V_HS1_TEMPN_R")
		)
	)
	(footprint ""
		(layer "F.Cu")
		(at 49.3014 -27.051 180)
		(property "Reference" "PU4"
			(at 3.5814 -1.42367 0)
			(unlocked yes)
			(layer "F.SilkS")
			(effects
				(font
					(size 0.7874 0.5842)
					(thickness 0.1524)
				)
				(justify left)
			)
		)
		(property "Value" ""
			(at 0 0 180)
			(layer "F.Fab")
			(effects
				(font
					(size 1.27 1.27)
				)
			)
		)
		(duplicate_pad_numbers_are_jumpers no)
		(fp_line
			(start 1.335278 1.100074)
			(end 1.335278 -1.100074)
			(stroke
				(width 0.1524)
				(type default)
			)
			(layer "F.SilkS")
		)
		(fp_line
			(start 1.335278 -1.100074)
			(end -1.335278 -1.100074)
			(stroke
				(width 0.1524)
				(type default)
			)
			(layer "F.SilkS")
		)
		(fp_line
			(start -1.335278 1.100074)
			(end 1.335278 1.100074)
			(stroke
				(width 0.1524)
				(type default)
			)
			(layer "F.SilkS")
		)
		(fp_line
			(start -1.335278 -1.100074)
			(end -1.335278 1.100074)
			(stroke
				(width 0.1524)
				(type default)
			)
			(layer "F.SilkS")
		)
		(fp_line
			(start 0.674878 1.100074)
			(end 0.674878 -1.100074)
			(stroke
				(width 0.1)
				(type default)
			)
			(layer "F.Fab")
		)
		(fp_line
			(start 0.674878 -1.100074)
			(end -0.674878 -1.100074)
			(stroke
				(width 0.1)
				(type default)
			)
			(layer "F.Fab")
		)
		(fp_line
			(start -0.674878 1.100074)
			(end 0.674878 1.100074)
			(stroke
				(width 0.1)
				(type default)
			)
			(layer "F.Fab")
		)
		(fp_line
			(start -0.674878 -1.100074)
			(end -0.674878 1.100074)
			(stroke
				(width 0.1)
				(type default)
			)
			(layer "F.Fab")
		)
		(pad "D" smd rect
			(at 0.8001 0 90)
			(size 0.6096 0.8128)
			(layers "F.Cu" "F.Mask" "F.Paste")
			(net "P52V_HS2_EN_DISCHARGE_N")
		)
		(pad "G" smd rect
			(at -0.8001 -0.649986 90)
			(size 0.6096 0.8128)
			(layers "F.Cu" "F.Mask" "F.Paste")
			(net "P52V_HS2_EN_DISCHARGE")
		)
		(pad "S" smd rect
			(at -0.8001 0.649986 90)
			(size 0.6096 0.8128)
			(layers "F.Cu" "F.Mask" "F.Paste")
			(net "GND")
		)
	)
	(footprint ""
		(layer "F.Cu")
		(at 142.93342 -73.025 180)
		(property "Reference" "PR7041"
			(at 0 0 180)
			(layer "F.SilkS")
			(hide yes)
			(effects
				(font
					(size 1.27 1.27)
				)
			)
		)
		(property "Value" ""
			(at 0 0 180)
			(layer "F.Fab")
			(effects
				(font
					(size 1.27 1.27)
				)
			)
		)
		(duplicate_pad_numbers_are_jumpers no)
		(fp_line
			(start 0.7874 0.4064)
			(end -0.7874 0.4064)
			(stroke
				(width 0.1524)
				(type default)
			)
			(layer "F.SilkS")
		)
		(fp_line
			(start 0.7874 -0.4064)
			(end 0.7874 0.4064)
			(stroke
				(width 0.1524)
				(type default)
			)
			(layer "F.SilkS")
		)
		(fp_line
			(start -0.7874 0.4064)
			(end -0.7874 -0.4064)
			(stroke
				(width 0.1524)
				(type default)
			)
			(layer "F.SilkS")
		)
		(fp_line
			(start -0.7874 -0.4064)
			(end 0.7874 -0.4064)
			(stroke
				(width 0.1524)
				(type default)
			)
			(layer "F.SilkS")
		)
		(fp_line
			(start 0.67945 0.3048)
			(end 0.120396 0.3048)
			(stroke
				(width 0.1)
				(type default)
			)
			(layer "F.Fab")
		)
		(fp_line
			(start 0.67945 -0.3048)
			(end 0.67945 0.3048)
			(stroke
				(width 0.1)
				(type default)
			)
			(layer "F.Fab")
		)
		(fp_line
			(start 0.12065 -0.2794)
			(end 0.12065 -0.3048)
			(stroke
				(width 0.1)
				(type default)
			)
			(layer "F.Fab")
		)
		(fp_line
			(start 0.12065 -0.3048)
			(end 0.67945 -0.3048)
			(stroke
				(width 0.1)
				(type default)
			)
			(layer "F.Fab")
		)
		(fp_line
			(start 0.120396 0.3048)
			(end 0.120396 0.2794)
			(stroke
				(width 0.1)
				(type default)
			)
			(layer "F.Fab")
		)
		(fp_line
			(start 0.120396 0.2794)
			(end -0.12065 0.2794)
			(stroke
				(width 0.1)
				(type default)
			)
			(layer "F.Fab")
		)
		(fp_line
			(start -0.12065 0.3048)
			(end -0.67945 0.3048)
			(stroke
				(width 0.1)
				(type default)
			)
			(layer "F.Fab")
		)
		(fp_line
			(start -0.12065 0.2794)
			(end -0.12065 0.3048)
			(stroke
				(width 0.1)
				(type default)
			)
			(layer "F.Fab")
		)
		(fp_line
			(start -0.12065 -0.2794)
			(end 0.12065 -0.2794)
			(stroke
				(width 0.1)
				(type default)
			)
			(layer "F.Fab")
		)
		(fp_line
			(start -0.12065 -0.305054)
			(end -0.12065 -0.2794)
			(stroke
				(width 0.1)
				(type default)
			)
			(layer "F.Fab")
		)
		(fp_line
			(start -0.67945 0.3048)
			(end -0.67945 -0.305054)
			(stroke
				(width 0.1)
				(type default)
			)
			(layer "F.Fab")
		)
		(fp_line
			(start -0.67945 -0.305054)
			(end -0.12065 -0.305054)
			(stroke
				(width 0.1)
				(type default)
			)
			(layer "F.Fab")
		)
		(pad "1" smd circle
			(at -0.40005 0 180)
			(size 0 0)
			(layers "F.Cu" "F.Mask" "F.Paste")
			(net "P52V_HS2_4287_S1P")
		)
		(pad "2" smd circle
			(at 0.40005 0 180)
			(size 0 0)
			(layers "F.Cu" "F.Mask" "F.Paste")
			(net "P52V_HS2_4287_S1N")
		)
	)
)
